# S9S_MB_2U (Grand Teton) — schematic netlist excerpt (pin names and nets, part order shuffled) for the footprints in the layout excerpt that follows; sources: Cadence DE-HDL packaged netlist, KiCad conversion of 03242023_DA0F0TMBIJ0_F0T_Motherboard_J_brd_V01_OCP.brd

PC569_P1_1  Q_CAP  22UF 16V 20% X6S  pkg C0805  page 285 : A = SW_P12V_PVCCIN_CPU1_FLT ; B = GND
C6  Q_CAP  10UF 16V 10% X6S  pkg C0805  page 83 : A = P12V_S3_AUX_CPU0_NVDIMM ; B = GND
C1867  Q_CAP  10UF 25V 10% X6S  pkg C0805  page 166 : A = P3V3_AUX ; B = GND

(kicad_pcb
	(version 20260206)
	(generator "pcbnew")
	(generator_version "10.0")
	(general
		(thickness 1.6)
		(legacy_teardrops no)
	)
	(paper "A4")
	(title_block
		(title "03242023_DA0F0TMBIJ0_F0T_Motherboard_J_brd_V01_OCP.brd")
		(comment 1 "Grand Teton / footprints 5908-5910 of 6105")
	)
	(layers
		(0 "F.Cu" signal "TOP")
		(4 "In1.Cu" signal "GND")
		(6 "In2.Cu" signal "IN1")
		(8 "In3.Cu" signal "GND1")
		(10 "In4.Cu" signal "IN2")
		(12 "In5.Cu" signal "GND2")
		(14 "In6.Cu" signal "IN3")
		(16 "In7.Cu" signal "GND3")
		(18 "In8.Cu" signal "VCC")
		(20 "In9.Cu" signal "VCC1")
		(22 "In10.Cu" signal "GND4")
		(24 "In11.Cu" signal "IN4")
		(26 "In12.Cu" signal "GND5")
		(28 "In13.Cu" signal "IN5")
		(30 "In14.Cu" signal "GND6")
		(32 "In15.Cu" signal "IN6")
		(34 "In16.Cu" signal "GND7")
		(2 "B.Cu" signal "BOTTOM")
		(9 "F.Adhes" user "F.Adhesive")
		(11 "B.Adhes" user "B.Adhesive")
		(13 "F.Paste" user "Package Geometry/Pastemask Top")
		(15 "B.Paste" user "Package Geometry/Pastemask Bottom")
		(5 "F.SilkS" user "Ref Des/Silkscreen Top")
		(7 "B.SilkS" user "Ref Des/Silkscreen Bottom")
		(1 "F.Mask" user "Board Geometry/Soldermask Top")
		(3 "B.Mask" user "Board Geometry/Soldermask Bottom")
		(17 "Dwgs.User" user "User.Drawings")
		(19 "Cmts.User" user "User.Comments")
		(21 "Eco1.User" user "User.Eco1")
		(23 "Eco2.User" user "User.Eco2")
		(25 "Edge.Cuts" user "Board Geometry/Outline")
		(27 "Margin" user)
		(31 "F.CrtYd" user "Package Geometry/Place Bound Top")
		(29 "B.CrtYd" user "Package Geometry/Place Bound Bottom")
		(35 "F.Fab" user "Ref Des/Assembly Top")
		(33 "B.Fab" user "Ref Des/Assembly Bottom")
	)
	(footprint ""
		(layer "B.Cu")
		(at 21.97608 -389.829548 -90)
		(property "Reference" "C1867"
			(at 0 0 90)
			(layer "B.SilkS")
			(hide yes)
			(effects
				(font
					(size 1.27 1.27)
				)
				(justify mirror)
			)
		)
		(property "Value" ""
			(at 0 0 90)
			(layer "B.Fab")
			(effects
				(font
					(size 1.27 1.27)
				)
				(justify mirror)
			)
		)
		(duplicate_pad_numbers_are_jumpers no)
		(fp_line
			(start -1.524 0.762)
			(end 1.524 0.762)
			(stroke
				(width 0.1524)
				(type default)
			)
			(layer "B.SilkS")
		)
		(fp_line
			(start 1.524 0.762)
			(end 1.524 -0.762)
			(stroke
				(width 0.1524)
				(type default)
			)
			(layer "B.SilkS")
		)
		(fp_line
			(start -1.524 -0.762)
			(end -1.524 0.762)
			(stroke
				(width 0.1524)
				(type default)
			)
			(layer "B.SilkS")
		)
		(fp_line
			(start 1.524 -0.762)
			(end -1.524 -0.762)
			(stroke
				(width 0.1524)
				(type default)
			)
			(layer "B.SilkS")
		)
		(fp_line
			(start -1.1049 0.724916)
			(end -1.1049 -0.724916)
			(stroke
				(width 0.1)
				(type default)
			)
			(layer "B.Fab")
		)
		(fp_line
			(start 1.1049 0.724916)
			(end -1.1049 0.724916)
			(stroke
				(width 0.1)
				(type default)
			)
			(layer "B.Fab")
		)
		(fp_line
			(start -1.1049 -0.724916)
			(end 1.1049 -0.724916)
			(stroke
				(width 0.1)
				(type default)
			)
			(layer "B.Fab")
		)
		(fp_line
			(start 1.1049 -0.724916)
			(end 1.1049 0.724916)
			(stroke
				(width 0.1)
				(type default)
			)
			(layer "B.Fab")
		)
		(pad "1" smd rect
			(at 0.889 0 270)
			(size 1.016 1.27)
			(layers "B.Cu" "B.Mask" "B.Paste")
			(net "P3V3_AUX")
		)
		(pad "2" smd rect
			(at -0.889 0 270)
			(size 1.016 1.27)
			(layers "B.Cu" "B.Mask" "B.Paste")
			(net "GND")
		)
	)
	(footprint ""
		(layer "B.Cu")
		(at 312.963814 -321.549776 -90)
		(property "Reference" "C6"
			(at 0 0 90)
			(layer "B.SilkS")
			(hide yes)
			(effects
				(font
					(size 1.27 1.27)
				)
				(justify mirror)
			)
		)
		(property "Value" ""
			(at 0 0 90)
			(layer "B.Fab")
			(effects
				(font
					(size 1.27 1.27)
				)
				(justify mirror)
			)
		)
		(duplicate_pad_numbers_are_jumpers no)
		(fp_line
			(start -1.524 0.762)
			(end 1.524 0.762)
			(stroke
				(width 0.1524)
				(type default)
			)
			(layer "B.SilkS")
		)
		(fp_line
			(start 1.524 0.762)
			(end 1.524 -0.762)
			(stroke
				(width 0.1524)
				(type default)
			)
			(layer "B.SilkS")
		)
		(fp_line
			(start -1.524 -0.762)
			(end -1.524 0.762)
			(stroke
				(width 0.1524)
				(type default)
			)
			(layer "B.SilkS")
		)
		(fp_line
			(start 1.524 -0.762)
			(end -1.524 -0.762)
			(stroke
				(width 0.1524)
				(type default)
			)
			(layer "B.SilkS")
		)
		(fp_line
			(start -1.1049 0.724916)
			(end -1.1049 -0.724916)
			(stroke
				(width 0.1)
				(type default)
			)
			(layer "B.Fab")
		)
		(fp_line
			(start 1.1049 0.724916)
			(end -1.1049 0.724916)
			(stroke
				(width 0.1)
				(type default)
			)
			(layer "B.Fab")
		)
		(fp_line
			(start -1.1049 -0.724916)
			(end 1.1049 -0.724916)
			(stroke
				(width 0.1)
				(type default)
			)
			(layer "B.Fab")
		)
		(fp_line
			(start 1.1049 -0.724916)
			(end 1.1049 0.724916)
			(stroke
				(width 0.1)
				(type default)
			)
			(layer "B.Fab")
		)
		(pad "1" smd rect
			(at 0.889 0 270)
			(size 1.016 1.27)
			(layers "B.Cu" "B.Mask" "B.Paste")
			(net "P12V_S3_AUX_CPU0_NVDIMM")
		)
		(pad "2" smd rect
			(at -0.889 0 270)
			(size 1.016 1.27)
			(layers "B.Cu" "B.Mask" "B.Paste")
			(net "GND")
		)
	)
	(footprint ""
		(layer "B.Cu")
		(at 98.5012 -337.607402 -90)
		(property "Reference" "PC569_P1_1"
			(at 0 0 90)
			(layer "B.SilkS")
			(hide yes)
			(effects
				(font
					(size 1.27 1.27)
				)
				(justify mirror)
			)
		)
		(property "Value" ""
			(at 0 0 90)
			(layer "B.Fab")
			(effects
				(font
					(size 1.27 1.27)
				)
				(justify mirror)
			)
		)
		(duplicate_pad_numbers_are_jumpers no)
		(fp_line
			(start -1.524 0.762)
			(end 1.524 0.762)
			(stroke
				(width 0.1524)
				(type default)
			)
			(layer "B.SilkS")
		)
		(fp_line
			(start 1.524 0.762)
			(end 1.524 -0.762)
			(stroke
				(width 0.1524)
				(type default)
			)
			(layer "B.SilkS")
		)
		(fp_line
			(start -1.524 -0.762)
			(end -1.524 0.762)
			(stroke
				(width 0.1524)
				(type default)
			)
			(layer "B.SilkS")
		)
		(fp_line
			(start 1.524 -0.762)
			(end -1.524 -0.762)
			(stroke
				(width 0.1524)
				(type default)
			)
			(layer "B.SilkS")
		)
		(fp_line
			(start -1.1049 0.724916)
			(end -1.1049 -0.724916)
			(stroke
				(width 0.1)
				(type default)
			)
			(layer "B.Fab")
		)
		(fp_line
			(start 1.1049 0.724916)
			(end -1.1049 0.724916)
			(stroke
				(width 0.1)
				(type default)
			)
			(layer "B.Fab")
		)
		(fp_line
			(start -1.1049 -0.724916)
			(end 1.1049 -0.724916)
			(stroke
				(width 0.1)
				(type default)
			)
			(layer "B.Fab")
		)
		(fp_line
			(start 1.1049 -0.724916)
			(end 1.1049 0.724916)
			(stroke
				(width 0.1)
				(type default)
			)
			(layer "B.Fab")
		)
		(pad "1" smd rect
			(at 0.889 0 270)
			(size 1.016 1.27)
			(layers "B.Cu" "B.Mask" "B.Paste")
			(net "SW_P12V_PVCCIN_CPU1_FLT")
		)
		(pad "2" smd rect
			(at -0.889 0 270)
			(size 1.016 1.27)
			(layers "B.Cu" "B.Mask" "B.Paste")
			(net "GND")
		)
	)
)
